(kicad_pcb
	(version 20260206)
	(generator "pcbnew")
	(generator_version "10.0")
	(general
		(thickness 1.6)
		(legacy_teardrops no)
	)
	(paper "A4")
	(title_block
		(title "v1-pdb — T6M_PDB_D_0927_0900.brd")
		(comment 1 "Open CloudServer (Microsoft) / footprint 318 of 321 (J7), pads 1-46 of 46")
	)
	(layers
		(0 "F.Cu" signal "TOP")
		(4 "In1.Cu" signal "GND")
		(6 "In2.Cu" signal "IN1")
		(8 "In3.Cu" signal "VCC")
		(10 "In4.Cu" signal "VCC1")
		(12 "In5.Cu" signal "IN2")
		(14 "In6.Cu" signal "GND1")
		(2 "B.Cu" signal "BOTTOM")
		(9 "F.Adhes" user "F.Adhesive")
		(11 "B.Adhes" user "B.Adhesive")
		(13 "F.Paste" user "Package Geometry/Pastemask Top")
		(15 "B.Paste" user "Package Geometry/Pastemask Bottom")
		(5 "F.SilkS" user "Ref Des/Silkscreen Top")
		(7 "B.SilkS" user "Ref Des/Silkscreen Bottom")
		(1 "F.Mask" user "Board Geometry/Soldermask Top")
		(3 "B.Mask" user "Board Geometry/Soldermask Bottom")
		(17 "Dwgs.User" user "User.Drawings")
		(19 "Cmts.User" user "User.Comments")
		(21 "Eco1.User" user "User.Eco1")
		(23 "Eco2.User" user "User.Eco2")
		(25 "Edge.Cuts" user "Board Geometry/Outline")
		(27 "Margin" user)
		(31 "F.CrtYd" user "Package Geometry/Place Bound Top")
		(29 "B.CrtYd" user "Package Geometry/Place Bound Bottom")
		(35 "F.Fab" user "Ref Des/Assembly Top")
		(33 "B.Fab" user "Ref Des/Assembly Bottom")
	)
	(footprint ""
		(layer "B.Cu")
		(at 44.03979 -8.26008 90)
		(property "Reference" "J7"
			(at 6.1214 -5.060442 0)
			(unlocked yes)
			(layer "B.SilkS")
			(effects
				(font
					(size 0.7874 0.5842)
					(thickness 0.1524)
				)
				(justify left mirror)
			)
		)
		(property "Value" ""
			(at 0 0 90)
			(layer "B.Fab")
			(effects
				(font
					(size 1.27 1.27)
				)
				(justify mirror)
			)
		)
		(duplicate_pad_numbers_are_jumpers no)
		(pad "" np_thru_hole circle
			(at -1.35001 -2.54)
			(size 2.5146 2.5146)
			(drill 2.5146)
			(layers "*.Cu" "*.Mask")
			(clearance 0.381)
			(thermal_gap 0.381)
		)
		(pad "" np_thru_hole circle
			(at 0 50.8)
			(size 2.5146 2.5146)
			(drill 2.5146)
			(layers "*.Cu" "*.Mask")
			(clearance 0.381)
			(thermal_gap 0.381)
		)
		(pad "P1" thru_hole rect
			(at 0 0)
			(size 1.1684 1.1684)
			(drill 0.762)
			(layers "*.Cu" "*.Mask")
			(remove_unused_layers no)
			(net "GND")
			(clearance 0.0508)
			(padstack
				(mode front_inner_back)
				(layer "Inner"
					(shape circle)
					(size 1.1684 1.1684)
					(clearance 0.0508)
				)
				(layer "B.Cu"
					(shape rect)
					(size 1.1684 1.1684)
					(thermal_gap 0.0508)
					(clearance 0.0508)
				)
			)
		)
		(pad "P2" thru_hole circle
			(at 0 2.54)
			(size 1.1684 1.1684)
			(drill 0.762)
			(layers "*.Cu" "*.Mask")
			(remove_unused_layers no)
			(net "GND")
			(clearance 0.0508)
			(thermal_gap 0.0508)
		)
		(pad "P3" thru_hole circle
			(at 0 5.08)
			(size 1.1684 1.1684)
			(drill 0.762)
			(layers "*.Cu" "*.Mask")
			(remove_unused_layers no)
			(net "GND")
			(clearance 0.0508)
			(thermal_gap 0.0508)
		)
		(pad "P4" thru_hole circle
			(at 0 7.62)
			(size 1.1684 1.1684)
			(drill 0.762)
			(layers "*.Cu" "*.Mask")
			(remove_unused_layers no)
			(net "GND")
			(clearance 0.0508)
			(thermal_gap 0.0508)
		)
		(pad "P5" thru_hole circle
			(at 0 10.16)
			(size 1.1684 1.1684)
			(drill 0.762)
			(layers "*.Cu" "*.Mask")
			(remove_unused_layers no)
			(net "GND")
			(clearance 0.0508)
			(thermal_gap 0.0508)
		)
		(pad "P6" thru_hole circle
			(at 0 12.7)
			(size 1.1684 1.1684)
			(drill 0.762)
			(layers "*.Cu" "*.Mask")
			(remove_unused_layers no)
			(net "GND")
			(clearance 0.0508)
			(thermal_gap 0.0508)
		)
		(pad "P7" thru_hole circle
			(at 0 15.24)
			(size 1.1684 1.1684)
			(drill 0.762)
			(layers "*.Cu" "*.Mask")
			(remove_unused_layers no)
			(net "GND")
			(clearance 0.0508)
			(thermal_gap 0.0508)
		)
		(pad "P8" thru_hole circle
			(at 0 17.78)
			(size 1.1684 1.1684)
			(drill 0.762)
			(layers "*.Cu" "*.Mask")
			(remove_unused_layers no)
			(net "GND")
			(clearance 0.0508)
			(thermal_gap 0.0508)
		)
		(pad "P9" thru_hole circle
			(at 0 20.32)
			(size 1.1684 1.1684)
			(drill 0.762)
			(layers "*.Cu" "*.Mask")
			(remove_unused_layers no)
			(net "P12V")
			(clearance 0.0508)
			(thermal_gap 0.0508)
		)
		(pad "P10" thru_hole circle
			(at 0 22.86)
			(size 1.1684 1.1684)
			(drill 0.762)
			(layers "*.Cu" "*.Mask")
			(remove_unused_layers no)
			(net "P12V")
			(clearance 0.0508)
			(thermal_gap 0.0508)
		)
		(pad "P11" thru_hole circle
			(at 0 25.4)
			(size 1.1684 1.1684)
			(drill 0.762)
			(layers "*.Cu" "*.Mask")
			(remove_unused_layers no)
			(net "P12V")
			(clearance 0.0508)
			(thermal_gap 0.0508)
		)
		(pad "P12" thru_hole circle
			(at 0 27.94)
			(size 1.1684 1.1684)
			(drill 0.762)
			(layers "*.Cu" "*.Mask")
			(remove_unused_layers no)
			(net "P12V")
			(clearance 0.0508)
			(thermal_gap 0.0508)
		)
		(pad "P13" thru_hole circle
			(at 0 30.48)
			(size 1.1684 1.1684)
			(drill 0.762)
			(layers "*.Cu" "*.Mask")
			(remove_unused_layers no)
			(net "P12V")
			(clearance 0.0508)
			(thermal_gap 0.0508)
		)
		(pad "P14" thru_hole circle
			(at 0 33.02)
			(size 1.1684 1.1684)
			(drill 0.762)
			(layers "*.Cu" "*.Mask")
			(remove_unused_layers no)
			(net "P12V")
			(clearance 0.0508)
			(thermal_gap 0.0508)
		)
		(pad "P15" thru_hole circle
			(at 0 35.56)
			(size 1.1684 1.1684)
			(drill 0.762)
			(layers "*.Cu" "*.Mask")
			(remove_unused_layers no)
			(net "P12V")
			(clearance 0.0508)
			(thermal_gap 0.0508)
		)
		(pad "P16" thru_hole circle
			(at 0 38.1)
			(size 1.1684 1.1684)
			(drill 0.762)
			(layers "*.Cu" "*.Mask")
			(remove_unused_layers no)
			(net "P12V")
			(clearance 0.0508)
			(thermal_gap 0.0508)
		)
		(pad "P17" thru_hole circle
			(at -2.70002 38.1)
			(size 1.1684 1.1684)
			(drill 0.762)
			(layers "*.Cu" "*.Mask")
			(remove_unused_layers no)
			(net "P12V")
			(clearance 0.0508)
			(thermal_gap 0.0508)
		)
		(pad "P18" thru_hole circle
			(at -2.70002 35.56)
			(size 1.1684 1.1684)
			(drill 0.762)
			(layers "*.Cu" "*.Mask")
			(remove_unused_layers no)
			(net "P12V")
			(clearance 0.0508)
			(thermal_gap 0.0508)
		)
		(pad "P19" thru_hole circle
			(at -2.70002 33.02)
			(size 1.1684 1.1684)
			(drill 0.762)
			(layers "*.Cu" "*.Mask")
			(remove_unused_layers no)
			(net "P12V")
			(clearance 0.0508)
			(thermal_gap 0.0508)
		)
		(pad "P20" thru_hole circle
			(at -2.70002 30.48)
			(size 1.1684 1.1684)
			(drill 0.762)
			(layers "*.Cu" "*.Mask")
			(remove_unused_layers no)
			(net "P12V")
			(clearance 0.0508)
			(thermal_gap 0.0508)
		)
		(pad "P21" thru_hole circle
			(at -2.70002 27.94)
			(size 1.1684 1.1684)
			(drill 0.762)
			(layers "*.Cu" "*.Mask")
			(remove_unused_layers no)
			(net "P12V")
			(clearance 0.0508)
			(thermal_gap 0.0508)
		)
		(pad "P22" thru_hole circle
			(at -2.70002 25.4)
			(size 1.1684 1.1684)
			(drill 0.762)
			(layers "*.Cu" "*.Mask")
			(remove_unused_layers no)
			(net "P12V")
			(clearance 0.0508)
			(thermal_gap 0.0508)
		)
		(pad "P23" thru_hole circle
			(at -2.70002 22.86)
			(size 1.1684 1.1684)
			(drill 0.762)
			(layers "*.Cu" "*.Mask")
			(remove_unused_layers no)
			(net "P12V")
			(clearance 0.0508)
			(thermal_gap 0.0508)
		)
		(pad "P24" thru_hole circle
			(at -2.70002 20.32)
			(size 1.1684 1.1684)
			(drill 0.762)
			(layers "*.Cu" "*.Mask")
			(remove_unused_layers no)
			(net "P12V")
			(clearance 0.0508)
			(thermal_gap 0.0508)
		)
		(pad "P25" thru_hole circle
			(at -2.70002 17.78)
			(size 1.1684 1.1684)
			(drill 0.762)
			(layers "*.Cu" "*.Mask")
			(remove_unused_layers no)
			(net "GND")
			(clearance 0.0508)
			(thermal_gap 0.0508)
		)
		(pad "P26" thru_hole circle
			(at -2.70002 15.24)
			(size 1.1684 1.1684)
			(drill 0.762)
			(layers "*.Cu" "*.Mask")
			(remove_unused_layers no)
			(net "GND")
			(clearance 0.0508)
			(thermal_gap 0.0508)
		)
		(pad "P27" thru_hole circle
			(at -2.70002 12.7)
			(size 1.1684 1.1684)
			(drill 0.762)
			(layers "*.Cu" "*.Mask")
			(remove_unused_layers no)
			(net "GND")
			(clearance 0.0508)
			(thermal_gap 0.0508)
		)
		(pad "P28" thru_hole circle
			(at -2.70002 10.16)
			(size 1.1684 1.1684)
			(drill 0.762)
			(layers "*.Cu" "*.Mask")
			(remove_unused_layers no)
			(net "GND")
			(clearance 0.0508)
			(thermal_gap 0.0508)
		)
		(pad "P29" thru_hole circle
			(at -2.70002 7.62)
			(size 1.1684 1.1684)
			(drill 0.762)
			(layers "*.Cu" "*.Mask")
			(remove_unused_layers no)
			(net "GND")
			(clearance 0.0508)
			(thermal_gap 0.0508)
		)
		(pad "P30" thru_hole circle
			(at -2.70002 5.08)
			(size 1.1684 1.1684)
			(drill 0.762)
			(layers "*.Cu" "*.Mask")
			(remove_unused_layers no)
			(net "GND")
			(clearance 0.0508)
			(thermal_gap 0.0508)
		)
		(pad "P31" thru_hole circle
			(at -2.70002 2.54)
			(size 1.1684 1.1684)
			(drill 0.762)
			(layers "*.Cu" "*.Mask")
			(remove_unused_layers no)
			(net "GND")
			(clearance 0.0508)
			(thermal_gap 0.0508)
		)
		(pad "P32" thru_hole circle
			(at -2.70002 0)
			(size 1.1684 1.1684)
			(drill 0.762)
			(layers "*.Cu" "*.Mask")
			(remove_unused_layers no)
			(net "GND")
			(clearance 0.0508)
			(thermal_gap 0.0508)
		)
		(pad "S1" thru_hole circle
			(at 0.55499 41.60012)
			(size 1.1684 1.1684)
			(drill 0.762)
			(layers "*.Cu" "*.Mask")
			(remove_unused_layers no)
			(net "T1_BLAD1_TXD")
			(clearance 0.0508)
			(thermal_gap 0.0508)
		)
		(pad "S2" thru_hole circle
			(at -0.71501 42.87012)
			(size 1.1684 1.1684)
			(drill 0.762)
			(layers "*.Cu" "*.Mask")
			(remove_unused_layers no)
			(net "T1_BLAD1_RXD")
			(clearance 0.0508)
			(thermal_gap 0.0508)
		)
		(pad "S3" thru_hole circle
			(at 0.55499 44.14012)
			(size 1.1684 1.1684)
			(drill 0.762)
			(layers "*.Cu" "*.Mask")
			(remove_unused_layers no)
			(net "T1_BLAD1_EN")
			(clearance 0.0508)
			(thermal_gap 0.0508)
		)
		(pad "S4" thru_hole circle
			(at -0.71501 45.41012)
			(size 1.1684 1.1684)
			(drill 0.762)
			(layers "*.Cu" "*.Mask")
			(remove_unused_layers no)
			(net "T1_BLAD2_EN")
			(clearance 0.0508)
			(thermal_gap 0.0508)
		)
		(pad "S5" thru_hole circle
			(at 0.55499 46.68012)
			(size 1.1684 1.1684)
			(drill 0.762)
			(layers "*.Cu" "*.Mask")
			(remove_unused_layers no)
			(net "T1_BLAD2_TXD")
			(clearance 0.0508)
			(thermal_gap 0.0508)
		)
		(pad "S6" thru_hole circle
			(at -0.71501 47.95012)
			(size 1.1684 1.1684)
			(drill 0.762)
			(layers "*.Cu" "*.Mask")
			(remove_unused_layers no)
			(net "T1_BLAD2_RXD")
			(clearance 0.0508)
			(thermal_gap 0.0508)
		)
		(pad "S7" thru_hole circle
			(at -3.25501 47.95012)
			(size 1.1684 1.1684)
			(drill 0.762)
			(layers "*.Cu" "*.Mask")
			(remove_unused_layers no)
			(net "T1_BLAD4_RXD")
			(clearance 0.0508)
			(thermal_gap 0.0508)
		)
		(pad "S8" thru_hole circle
			(at -1.98501 46.68012)
			(size 1.1684 1.1684)
			(drill 0.762)
			(layers "*.Cu" "*.Mask")
			(remove_unused_layers no)
			(net "T1_BLAD4_TXD")
			(clearance 0.0508)
			(thermal_gap 0.0508)
		)
		(pad "S9" thru_hole circle
			(at -3.25501 45.41012)
			(size 1.1684 1.1684)
			(drill 0.762)
			(layers "*.Cu" "*.Mask")
			(remove_unused_layers no)
			(net "T1_BLAD4_EN")
			(clearance 0.0508)
			(thermal_gap 0.0508)
		)
		(pad "S10" thru_hole circle
			(at -1.98501 44.14012)
			(size 1.1684 1.1684)
			(drill 0.762)
			(layers "*.Cu" "*.Mask")
			(remove_unused_layers no)
			(net "T1_BLAD3_EN")
			(clearance 0.0508)
			(thermal_gap 0.0508)
		)
		(pad "S11" thru_hole circle
			(at -3.25501 42.87012)
			(size 1.1684 1.1684)
			(drill 0.762)
			(layers "*.Cu" "*.Mask")
			(remove_unused_layers no)
			(net "T1_BLAD3_RXD")
			(clearance 0.0508)
			(thermal_gap 0.0508)
		)
		(pad "S12" thru_hole circle
			(at -1.98501 41.60012)
			(size 1.1684 1.1684)
			(drill 0.762)
			(layers "*.Cu" "*.Mask")
			(remove_unused_layers no)
			(net "T1_BLAD3_TXD")
			(clearance 0.0508)
			(thermal_gap 0.0508)
		)
	)
)
